# TIMECARD (Time Appliance Project (Time Card)) — schematic netlist excerpt (pin names and nets, part order shuffled) for the footprints in the layout excerpt that follows; sources: Cadence DE-HDL packaged netlist, KiCad conversion of R4006-B0001-02_R01.brd

L23  FERRITEBEAD  26OHM 25%  pkg SMC_0603R_H030  page 33 : \1\ = UNNAMED_525_CAPACITOR_I7_1 ; \2\ = UNNAMED_525_CAPACITOR_I16_1

(kicad_pcb
	(version 20260206)
	(generator "pcbnew")
	(generator_version "10.0")
	(general
		(thickness 1.6)
		(legacy_teardrops no)
	)
	(paper "A4")
	(title_block
		(title "timecard-production-celestica-r4006 — R4006-B0001-02_R01.brd")
		(comment 1 "Time Appliance Project (Time Card) / footprints 501-501 of 1113")
	)
	(layers
		(0 "F.Cu" signal "TOP")
		(4 "In1.Cu" signal "L02_GND1")
		(6 "In2.Cu" signal "L03_SIG1")
		(8 "In3.Cu" signal "L04_GND2")
		(10 "In4.Cu" signal "L05_VCC1")
		(12 "In5.Cu" signal "L06_VCC2")
		(14 "In6.Cu" signal "L07_GND3")
		(16 "In7.Cu" signal "L08_SIG2")
		(18 "In8.Cu" signal "L09_GND4")
		(2 "B.Cu" signal "BOTTOM")
		(9 "F.Adhes" user "F.Adhesive")
		(11 "B.Adhes" user "B.Adhesive")
		(13 "F.Paste" user "Package Geometry/Pastemask Top")
		(15 "B.Paste" user "Package Geometry/Pastemask Bottom")
		(5 "F.SilkS" user "Ref Des/Silkscreen Top")
		(7 "B.SilkS" user "Ref Des/Silkscreen Bottom")
		(1 "F.Mask" user "Board Geometry/Soldermask Top")
		(3 "B.Mask" user "Board Geometry/Soldermask Bottom")
		(17 "Dwgs.User" user "User.Drawings")
		(19 "Cmts.User" user "User.Comments")
		(21 "Eco1.User" user "User.Eco1")
		(23 "Eco2.User" user "User.Eco2")
		(25 "Edge.Cuts" user "Board Geometry/Outline")
		(27 "Margin" user)
		(31 "F.CrtYd" user "Package Geometry/Place Bound Top")
		(29 "B.CrtYd" user "Package Geometry/Place Bound Bottom")
		(35 "F.Fab" user "Ref Des/Assembly Top")
		(33 "B.Fab" user "Ref Des/Assembly Bottom")
	)
	(footprint ""
		(layer "F.Cu")
		(at 44.704 -80.264 -90)
		(property "Reference" "L23"
			(at -0.1905 -3.84937 90)
			(unlocked yes)
			(layer "F.SilkS")
			(effects
				(font
					(size 0.7874 0.5842)
					(thickness 0.1524)
				)
				(justify left)
			)
		)
		(property "Value" "VAL*"
			(at -0.9398 3.70967 270)
			(unlocked yes)
			(layer "F.Fab")
			(hide yes)
			(effects
				(font
					(size 0.7874 0.5842)
					(thickness 0.1524)
				)
				(justify left)
			)
		)
		(property "Tolerance" "TOL*"
			(at -0.9906 5.00507 270)
			(unlocked yes)
			(layer "Cmts.User")
			(hide yes)
			(effects
				(font
					(size 0.7874 0.5842)
					(thickness 0.1524)
				)
				(justify left)
			)
		)
		(property "User Part Number" "PARTNUM*"
			(at -2.54 2.46507 270)
			(unlocked yes)
			(layer "Cmts.User")
			(hide yes)
			(effects
				(font
					(size 0.7874 0.5842)
					(thickness 0.1524)
				)
				(justify left)
			)
		)
		(property "Device Type" "FERRITEBEAD-G191-10101-01,26OHA"
			(at -0.9906 1.22047 270)
			(unlocked yes)
			(layer "F.Fab")
			(hide yes)
			(effects
				(font
					(size 0.7874 0.5842)
					(thickness 0.1524)
				)
				(justify left)
			)
		)
		(duplicate_pad_numbers_are_jumpers no)
		(fp_line
			(start -1.3208 0.7112)
			(end -1.3208 -0.7112)
			(stroke
				(width 0.1)
				(type default)
			)
			(layer "F.SilkS")
		)
		(fp_line
			(start 1.3208 0.7112)
			(end -1.3208 0.7112)
			(stroke
				(width 0.1)
				(type default)
			)
			(layer "F.SilkS")
		)
		(fp_line
			(start -1.3208 -0.7112)
			(end 1.3208 -0.7112)
			(stroke
				(width 0.1)
				(type default)
			)
			(layer "F.SilkS")
		)
		(fp_line
			(start 1.3208 -0.7112)
			(end 1.3208 0.7112)
			(stroke
				(width 0.1)
				(type default)
			)
			(layer "F.SilkS")
		)
		(fp_rect
			(start -1.3208 0.7112)
			(end 1.3208 -0.7112)
			(stroke
				(width 0)
				(type default)
			)
			(fill no)
			(layer "F.CrtYd")
		)
		(fp_line
			(start -0.8128 0.4572)
			(end -0.8128 -0.4572)
			(stroke
				(width 0.1)
				(type default)
			)
			(layer "F.Fab")
		)
		(fp_line
			(start 0.8128 0.4572)
			(end -0.8128 0.4572)
			(stroke
				(width 0.1)
				(type default)
			)
			(layer "F.Fab")
		)
		(fp_line
			(start -0.8128 -0.4572)
			(end 0.8128 -0.4572)
			(stroke
				(width 0.1)
				(type default)
			)
			(layer "F.Fab")
		)
		(fp_line
			(start 0.8128 -0.4572)
			(end 0.8128 0.4572)
			(stroke
				(width 0.1)
				(type default)
			)
			(layer "F.Fab")
		)
		(pad "1" smd rect
			(at -0.6858 0 270)
			(size 0.762 0.8636)
			(layers "F.Cu" "F.Mask" "F.Paste")
			(net "UNNAMED_525_CAPACITOR_I7_1")
		)
		(pad "2" smd rect
			(at 0.6858 0 270)
			(size 0.762 0.8636)
			(layers "F.Cu" "F.Mask" "F.Paste")
			(net "UNNAMED_525_CAPACITOR_I16_1")
		)
		(zone
			(layer "F.Cu")
			(hatch none 0.5)
			(connect_pads
				(clearance 0)
			)
			(min_thickness 0.25)
			(keepout
				(tracks not_allowed)
				(vias allowed)
				(pads allowed)
				(copperpour not_allowed)
				(footprints allowed)
			)
			(placement
				(enabled no)
				(sheetname "")
			)
			(fill
				(thermal_gap 0.5)
				(thermal_bridge_width 0.5)
				(island_removal_mode 0)
			)
			(polygon
				(pts
					(xy 44.2468 -80.4164) (xy 44.2468 -80.1116) (xy 45.1612 -80.1116) (xy 45.1612 -80.4164)
				)
			)
		)
		(zone
			(layer "F.Cu")
			(hatch none 0.5)
			(connect_pads
				(clearance 0)
			)
			(min_thickness 0.25)
			(keepout
				(tracks allowed)
				(vias not_allowed)
				(pads allowed)
				(copperpour not_allowed)
				(footprints allowed)
			)
			(placement
				(enabled no)
				(sheetname "")
			)
			(fill
				(thermal_gap 0.5)
				(thermal_bridge_width 0.5)
				(island_removal_mode 0)
			)
			(polygon
				(pts
					(xy 44.2468 -80.4164) (xy 44.2468 -80.1116) (xy 45.1612 -80.1116) (xy 45.1612 -80.4164)
				)
			)
		)
	)
)
